# S9S_MB_2U (Grand Teton) — schematic netlist excerpt (pin names and nets, part order shuffled) for the footprints in the layout excerpt that follows; sources: Cadence DE-HDL packaged netlist, KiCad conversion of 03242023_DA0F0TMBIJ0_F0T_Motherboard_J_brd_V01_OCP.brd

R4182  Q_RES  33.2 1% CHIP  pkg 0402LF  page 170 : A = SMB_LM75_1_3V3AUX_SDA ; B = SMB_LM75_1_3V3AUX_SDA_R1
C239  Q_CAP  10UF 6.3V 20% X6S  pkg C0402  page 77 : A = PVCCIN_CPU1 ; B = GND

(kicad_pcb
	(version 20260206)
	(generator "pcbnew")
	(generator_version "10.0")
	(general
		(thickness 1.6)
		(legacy_teardrops no)
	)
	(paper "A4")
	(title_block
		(title "03242023_DA0F0TMBIJ0_F0T_Motherboard_J_brd_V01_OCP.brd")
		(comment 1 "Grand Teton / footprints 4031-4032 of 6105")
	)
	(layers
		(0 "F.Cu" signal "TOP")
		(4 "In1.Cu" signal "GND")
		(6 "In2.Cu" signal "IN1")
		(8 "In3.Cu" signal "GND1")
		(10 "In4.Cu" signal "IN2")
		(12 "In5.Cu" signal "GND2")
		(14 "In6.Cu" signal "IN3")
		(16 "In7.Cu" signal "GND3")
		(18 "In8.Cu" signal "VCC")
		(20 "In9.Cu" signal "VCC1")
		(22 "In10.Cu" signal "GND4")
		(24 "In11.Cu" signal "IN4")
		(26 "In12.Cu" signal "GND5")
		(28 "In13.Cu" signal "IN5")
		(30 "In14.Cu" signal "GND6")
		(32 "In15.Cu" signal "IN6")
		(34 "In16.Cu" signal "GND7")
		(2 "B.Cu" signal "BOTTOM")
		(9 "F.Adhes" user "F.Adhesive")
		(11 "B.Adhes" user "B.Adhesive")
		(13 "F.Paste" user "Package Geometry/Pastemask Top")
		(15 "B.Paste" user "Package Geometry/Pastemask Bottom")
		(5 "F.SilkS" user "Ref Des/Silkscreen Top")
		(7 "B.SilkS" user "Ref Des/Silkscreen Bottom")
		(1 "F.Mask" user "Board Geometry/Soldermask Top")
		(3 "B.Mask" user "Board Geometry/Soldermask Bottom")
		(17 "Dwgs.User" user "User.Drawings")
		(19 "Cmts.User" user "User.Comments")
		(21 "Eco1.User" user "User.Eco1")
		(23 "Eco2.User" user "User.Eco2")
		(25 "Edge.Cuts" user "Board Geometry/Outline")
		(27 "Margin" user)
		(31 "F.CrtYd" user "Package Geometry/Place Bound Top")
		(29 "B.CrtYd" user "Package Geometry/Place Bound Bottom")
		(35 "F.Fab" user "Ref Des/Assembly Top")
		(33 "B.Fab" user "Ref Des/Assembly Bottom")
	)
	(footprint ""
		(layer "F.Cu")
		(at 285.268162 -16.39443)
		(property "Reference" "R4182"
			(at 0 0 0)
			(layer "F.SilkS")
			(hide yes)
			(effects
				(font
					(size 1.27 1.27)
				)
			)
		)
		(property "Value" ""
			(at 0 0 0)
			(layer "F.Fab")
			(effects
				(font
					(size 1.27 1.27)
				)
			)
		)
		(duplicate_pad_numbers_are_jumpers no)
		(fp_line
			(start -0.7874 -0.4064)
			(end 0.7874 -0.4064)
			(stroke
				(width 0.1524)
				(type default)
			)
			(layer "F.SilkS")
		)
		(fp_line
			(start -0.7874 0.4064)
			(end -0.7874 -0.4064)
			(stroke
				(width 0.1524)
				(type default)
			)
			(layer "F.SilkS")
		)
		(fp_line
			(start 0.7874 -0.4064)
			(end 0.7874 0.4064)
			(stroke
				(width 0.1524)
				(type default)
			)
			(layer "F.SilkS")
		)
		(fp_line
			(start 0.7874 0.4064)
			(end -0.7874 0.4064)
			(stroke
				(width 0.1524)
				(type default)
			)
			(layer "F.SilkS")
		)
		(fp_line
			(start -0.67945 -0.305054)
			(end -0.12065 -0.305054)
			(stroke
				(width 0.1)
				(type default)
			)
			(layer "F.Fab")
		)
		(fp_line
			(start -0.67945 0.3048)
			(end -0.67945 -0.305054)
			(stroke
				(width 0.1)
				(type default)
			)
			(layer "F.Fab")
		)
		(fp_line
			(start -0.12065 -0.305054)
			(end -0.12065 -0.2794)
			(stroke
				(width 0.1)
				(type default)
			)
			(layer "F.Fab")
		)
		(fp_line
			(start -0.12065 -0.2794)
			(end 0.12065 -0.2794)
			(stroke
				(width 0.1)
				(type default)
			)
			(layer "F.Fab")
		)
		(fp_line
			(start -0.12065 0.2794)
			(end -0.12065 0.3048)
			(stroke
				(width 0.1)
				(type default)
			)
			(layer "F.Fab")
		)
		(fp_line
			(start -0.12065 0.3048)
			(end -0.67945 0.3048)
			(stroke
				(width 0.1)
				(type default)
			)
			(layer "F.Fab")
		)
		(fp_line
			(start 0.120396 0.2794)
			(end -0.12065 0.2794)
			(stroke
				(width 0.1)
				(type default)
			)
			(layer "F.Fab")
		)
		(fp_line
			(start 0.120396 0.3048)
			(end 0.120396 0.2794)
			(stroke
				(width 0.1)
				(type default)
			)
			(layer "F.Fab")
		)
		(fp_line
			(start 0.12065 -0.3048)
			(end 0.67945 -0.3048)
			(stroke
				(width 0.1)
				(type default)
			)
			(layer "F.Fab")
		)
		(fp_line
			(start 0.12065 -0.2794)
			(end 0.12065 -0.3048)
			(stroke
				(width 0.1)
				(type default)
			)
			(layer "F.Fab")
		)
		(fp_line
			(start 0.67945 -0.3048)
			(end 0.67945 0.3048)
			(stroke
				(width 0.1)
				(type default)
			)
			(layer "F.Fab")
		)
		(fp_line
			(start 0.67945 0.3048)
			(end 0.120396 0.3048)
			(stroke
				(width 0.1)
				(type default)
			)
			(layer "F.Fab")
		)
		(pad "1" smd circle
			(at -0.40005 0)
			(size 0 0)
			(layers "F.Cu" "F.Mask" "F.Paste")
			(net "SMB_LM75_1_3V3AUX_SDA")
		)
		(pad "2" smd circle
			(at 0.40005 0)
			(size 0 0)
			(layers "F.Cu" "F.Mask" "F.Paste")
			(net "SMB_LM75_1_3V3AUX_SDA_R1")
		)
	)
	(footprint ""
		(layer "F.Cu")
		(at 119.508016 -244.032024 90)
		(property "Reference" "C239"
			(at 0 0 90)
			(layer "F.SilkS")
			(hide yes)
			(effects
				(font
					(size 1.27 1.27)
				)
			)
		)
		(property "Value" ""
			(at 0 0 90)
			(layer "F.Fab")
			(effects
				(font
					(size 1.27 1.27)
				)
			)
		)
		(duplicate_pad_numbers_are_jumpers no)
		(fp_line
			(start 0.7874 -0.4064)
			(end 0.7874 0.4064)
			(stroke
				(width 0.1524)
				(type default)
			)
			(layer "F.SilkS")
		)
		(fp_line
			(start -0.7874 -0.4064)
			(end 0.7874 -0.4064)
			(stroke
				(width 0.1524)
				(type default)
			)
			(layer "F.SilkS")
		)
		(fp_line
			(start 0.7874 0.4064)
			(end -0.7874 0.4064)
			(stroke
				(width 0.1524)
				(type default)
			)
			(layer "F.SilkS")
		)
		(fp_line
			(start -0.7874 0.4064)
			(end -0.7874 -0.4064)
			(stroke
				(width 0.1524)
				(type default)
			)
			(layer "F.SilkS")
		)
		(fp_line
			(start -0.12065 -0.305054)
			(end -0.12065 -0.2794)
			(stroke
				(width 0.1)
				(type default)
			)
			(layer "F.Fab")
		)
		(fp_line
			(start -0.67945 -0.305054)
			(end -0.12065 -0.305054)
			(stroke
				(width 0.1)
				(type default)
			)
			(layer "F.Fab")
		)
		(fp_line
			(start 0.67945 -0.3048)
			(end 0.67945 0.3048)
			(stroke
				(width 0.1)
				(type default)
			)
			(layer "F.Fab")
		)
		(fp_line
			(start 0.12065 -0.3048)
			(end 0.67945 -0.3048)
			(stroke
				(width 0.1)
				(type default)
			)
			(layer "F.Fab")
		)
		(fp_line
			(start 0.12065 -0.2794)
			(end 0.12065 -0.3048)
			(stroke
				(width 0.1)
				(type default)
			)
			(layer "F.Fab")
		)
		(fp_line
			(start -0.12065 -0.2794)
			(end 0.12065 -0.2794)
			(stroke
				(width 0.1)
				(type default)
			)
			(layer "F.Fab")
		)
		(fp_line
			(start 0.120396 0.2794)
			(end -0.12065 0.2794)
			(stroke
				(width 0.1)
				(type default)
			)
			(layer "F.Fab")
		)
		(fp_line
			(start -0.12065 0.2794)
			(end -0.12065 0.3048)
			(stroke
				(width 0.1)
				(type default)
			)
			(layer "F.Fab")
		)
		(fp_line
			(start 0.67945 0.3048)
			(end 0.120396 0.3048)
			(stroke
				(width 0.1)
				(type default)
			)
			(layer "F.Fab")
		)
		(fp_line
			(start 0.120396 0.3048)
			(end 0.120396 0.2794)
			(stroke
				(width 0.1)
				(type default)
			)
			(layer "F.Fab")
		)
		(fp_line
			(start -0.12065 0.3048)
			(end -0.67945 0.3048)
			(stroke
				(width 0.1)
				(type default)
			)
			(layer "F.Fab")
		)
		(fp_line
			(start -0.67945 0.3048)
			(end -0.67945 -0.305054)
			(stroke
				(width 0.1)
				(type default)
			)
			(layer "F.Fab")
		)
		(pad "1" smd circle
			(at -0.40005 0 90)
			(size 0 0)
			(layers "F.Cu" "F.Mask" "F.Paste")
			(net "PVCCIN_CPU1")
		)
		(pad "2" smd circle
			(at 0.40005 0 90)
			(size 0 0)
			(layers "F.Cu" "F.Mask" "F.Paste")
			(net "GND")
		)
	)
)
